(kicad_pcb
	(version 20260206)
	(generator "pcbnew")
	(generator_version "10.0")
	(general
		(thickness 1.6)
		(legacy_teardrops no)
	)
	(paper "A4")
	(title_block
		(title "01162023_DA0F0TEBIF0_F0T_Expander_BD_F_brd_V02_OCP.brd")
		(comment 1 "Grand Teton / footprints 4887-4890 of 9728")
	)
	(layers
		(0 "F.Cu" signal "TOP")
		(4 "In1.Cu" signal "GND")
		(6 "In2.Cu" signal "VCC")
		(8 "In3.Cu" signal "VCC1")
		(10 "In4.Cu" signal "GND1")
		(12 "In5.Cu" signal "IN1")
		(14 "In6.Cu" signal "GND2")
		(16 "In7.Cu" signal "IN2")
		(18 "In8.Cu" signal "GND3")
		(20 "In9.Cu" signal "IN3")
		(22 "In10.Cu" signal "GND4")
		(24 "In11.Cu" signal "IN4")
		(26 "In12.Cu" signal "GND5")
		(28 "In13.Cu" signal "IN5")
		(30 "In14.Cu" signal "GND6")
		(32 "In15.Cu" signal "IN6")
		(34 "In16.Cu" signal "GND7")
		(2 "B.Cu" signal "BOTTOM")
		(9 "F.Adhes" user "F.Adhesive")
		(11 "B.Adhes" user "B.Adhesive")
		(13 "F.Paste" user "Package Geometry/Pastemask Top")
		(15 "B.Paste" user "Package Geometry/Pastemask Bottom")
		(5 "F.SilkS" user "Ref Des/Silkscreen Top")
		(7 "B.SilkS" user "Ref Des/Silkscreen Bottom")
		(1 "F.Mask" user "Board Geometry/Soldermask Top")
		(3 "B.Mask" user "Board Geometry/Soldermask Bottom")
		(17 "Dwgs.User" user "User.Drawings")
		(19 "Cmts.User" user "User.Comments")
		(21 "Eco1.User" user "User.Eco1")
		(23 "Eco2.User" user "User.Eco2")
		(25 "Edge.Cuts" user "Board Geometry/Outline")
		(27 "Margin" user)
		(31 "F.CrtYd" user "Package Geometry/Place Bound Top")
		(29 "B.CrtYd" user "Package Geometry/Place Bound Bottom")
		(35 "F.Fab" user "Ref Des/Assembly Top")
		(33 "B.Fab" user "Ref Des/Assembly Bottom")
	)
	(footprint ""
		(layer "F.Cu")
		(at 10.615168 -251.312426 -90)
		(property "Reference" "C4228"
			(at 0 0 270)
			(layer "F.SilkS")
			(hide yes)
			(effects
				(font
					(size 1.27 1.27)
				)
			)
		)
		(property "Value" ""
			(at 0 0 270)
			(layer "F.Fab")
			(effects
				(font
					(size 1.27 1.27)
				)
			)
		)
		(duplicate_pad_numbers_are_jumpers no)
		(fp_line
			(start -1.2954 0.5842)
			(end -1.2954 -0.5842)
			(stroke
				(width 0.1524)
				(type default)
			)
			(layer "F.SilkS")
		)
		(fp_line
			(start 1.2954 0.5842)
			(end -1.2954 0.5842)
			(stroke
				(width 0.1524)
				(type default)
			)
			(layer "F.SilkS")
		)
		(fp_line
			(start -1.2954 -0.5842)
			(end 1.2954 -0.5842)
			(stroke
				(width 0.1524)
				(type default)
			)
			(layer "F.SilkS")
		)
		(fp_line
			(start 1.2954 -0.5842)
			(end 1.2954 0.5842)
			(stroke
				(width 0.1524)
				(type default)
			)
			(layer "F.SilkS")
		)
		(fp_line
			(start -0.8636 0.4572)
			(end -0.8636 0.4064)
			(stroke
				(width 0.1)
				(type default)
			)
			(layer "F.Fab")
		)
		(fp_line
			(start 0.8636 0.4572)
			(end -0.8636 0.4572)
			(stroke
				(width 0.1)
				(type default)
			)
			(layer "F.Fab")
		)
		(fp_line
			(start -1.1938 0.4064)
			(end -1.1938 -0.4064)
			(stroke
				(width 0.1)
				(type default)
			)
			(layer "F.Fab")
		)
		(fp_line
			(start -0.8636 0.4064)
			(end -1.1938 0.4064)
			(stroke
				(width 0.1)
				(type default)
			)
			(layer "F.Fab")
		)
		(fp_line
			(start 0.8636 0.4064)
			(end 0.8636 0.4572)
			(stroke
				(width 0.1)
				(type default)
			)
			(layer "F.Fab")
		)
		(fp_line
			(start 1.1938 0.4064)
			(end 0.8636 0.4064)
			(stroke
				(width 0.1)
				(type default)
			)
			(layer "F.Fab")
		)
		(fp_line
			(start -1.1938 -0.4064)
			(end -0.8636 -0.4064)
			(stroke
				(width 0.1)
				(type default)
			)
			(layer "F.Fab")
		)
		(fp_line
			(start -0.8636 -0.4064)
			(end -0.8636 -0.4572)
			(stroke
				(width 0.1)
				(type default)
			)
			(layer "F.Fab")
		)
		(fp_line
			(start 0.8636 -0.4064)
			(end 1.1938 -0.4064)
			(stroke
				(width 0.1)
				(type default)
			)
			(layer "F.Fab")
		)
		(fp_line
			(start 1.1938 -0.4064)
			(end 1.1938 0.4064)
			(stroke
				(width 0.1)
				(type default)
			)
			(layer "F.Fab")
		)
		(fp_line
			(start -0.8636 -0.4572)
			(end 0.8636 -0.4572)
			(stroke
				(width 0.1)
				(type default)
			)
			(layer "F.Fab")
		)
		(fp_line
			(start 0.8636 -0.4572)
			(end 0.8636 -0.4064)
			(stroke
				(width 0.1)
				(type default)
			)
			(layer "F.Fab")
		)
		(pad "1" smd rect
			(at -0.7366 0 180)
			(size 0.7112 0.8128)
			(layers "F.Cu" "F.Mask" "F.Paste")
			(net "P1V25_SERDES_VDDPLL_PEX0_C2")
		)
		(pad "2" smd rect
			(at 0.7366 0 180)
			(size 0.7112 0.8128)
			(layers "F.Cu" "F.Mask" "F.Paste")
			(net "GND")
		)
	)
	(footprint ""
		(layer "F.Cu")
		(at 338.838286 -93.11894 -90)
		(property "Reference" "R1185"
			(at 0 0 270)
			(layer "F.SilkS")
			(hide yes)
			(effects
				(font
					(size 1.27 1.27)
				)
			)
		)
		(property "Value" ""
			(at 0 0 270)
			(layer "F.Fab")
			(effects
				(font
					(size 1.27 1.27)
				)
			)
		)
		(duplicate_pad_numbers_are_jumpers no)
		(fp_line
			(start 0.7874 0.4064)
			(end -0.7874 0.4064)
			(stroke
				(width 0.1524)
				(type default)
			)
			(layer "F.SilkS")
		)
		(fp_line
			(start -0.67945 0.3048)
			(end -0.67945 -0.305054)
			(stroke
				(width 0.1)
				(type default)
			)
			(layer "F.Fab")
		)
		(fp_line
			(start -0.12065 0.3048)
			(end -0.67945 0.3048)
			(stroke
				(width 0.1)
				(type default)
			)
			(layer "F.Fab")
		)
		(fp_line
			(start 0.120396 0.3048)
			(end 0.120396 0.2794)
			(stroke
				(width 0.1)
				(type default)
			)
			(layer "F.Fab")
		)
		(fp_line
			(start 0.67945 0.3048)
			(end 0.120396 0.3048)
			(stroke
				(width 0.1)
				(type default)
			)
			(layer "F.Fab")
		)
		(fp_line
			(start -0.12065 0.2794)
			(end -0.12065 0.3048)
			(stroke
				(width 0.1)
				(type default)
			)
			(layer "F.Fab")
		)
		(fp_line
			(start 0.120396 0.2794)
			(end -0.12065 0.2794)
			(stroke
				(width 0.1)
				(type default)
			)
			(layer "F.Fab")
		)
		(fp_line
			(start -0.12065 -0.2794)
			(end 0.12065 -0.2794)
			(stroke
				(width 0.1)
				(type default)
			)
			(layer "F.Fab")
		)
		(fp_line
			(start 0.12065 -0.2794)
			(end 0.12065 -0.3048)
			(stroke
				(width 0.1)
				(type default)
			)
			(layer "F.Fab")
		)
		(fp_line
			(start 0.12065 -0.3048)
			(end 0.67945 -0.3048)
			(stroke
				(width 0.1)
				(type default)
			)
			(layer "F.Fab")
		)
		(fp_line
			(start 0.67945 -0.3048)
			(end 0.67945 0.3048)
			(stroke
				(width 0.1)
				(type default)
			)
			(layer "F.Fab")
		)
		(fp_line
			(start -0.67945 -0.305054)
			(end -0.12065 -0.305054)
			(stroke
				(width 0.1)
				(type default)
			)
			(layer "F.Fab")
		)
		(fp_line
			(start -0.12065 -0.305054)
			(end -0.12065 -0.2794)
			(stroke
				(width 0.1)
				(type default)
			)
			(layer "F.Fab")
		)
		(pad "1" smd circle
			(at -0.40005 0 270)
			(size 0 0)
			(layers "F.Cu" "F.Mask" "F.Paste")
			(net "CLK_100M_DB800ZL_SSD15_R_DN")
		)
		(pad "2" smd circle
			(at 0.40005 0 270)
			(size 0 0)
			(layers "F.Cu" "F.Mask" "F.Paste")
			(net "CLK_100M_DB800ZL_SSD15_DN")
		)
	)
	(footprint ""
		(layer "F.Cu")
		(at 168.367964 -52.035456 180)
		(property "Reference" "R864"
			(at 0 0 180)
			(layer "F.SilkS")
			(hide yes)
			(effects
				(font
					(size 1.27 1.27)
				)
			)
		)
		(property "Value" ""
			(at 0 0 180)
			(layer "F.Fab")
			(effects
				(font
					(size 1.27 1.27)
				)
			)
		)
		(duplicate_pad_numbers_are_jumpers no)
		(fp_line
			(start 0.7874 0.4064)
			(end -0.7874 0.4064)
			(stroke
				(width 0.1524)
				(type default)
			)
			(layer "F.SilkS")
		)
		(fp_line
			(start 0.7874 -0.4064)
			(end 0.7874 0.4064)
			(stroke
				(width 0.1524)
				(type default)
			)
			(layer "F.SilkS")
		)
		(fp_line
			(start -0.7874 0.4064)
			(end -0.7874 -0.4064)
			(stroke
				(width 0.1524)
				(type default)
			)
			(layer "F.SilkS")
		)
		(fp_line
			(start -0.7874 -0.4064)
			(end 0.7874 -0.4064)
			(stroke
				(width 0.1524)
				(type default)
			)
			(layer "F.SilkS")
		)
		(fp_line
			(start 0.67945 0.3048)
			(end 0.120396 0.3048)
			(stroke
				(width 0.1)
				(type default)
			)
			(layer "F.Fab")
		)
		(fp_line
			(start 0.67945 -0.3048)
			(end 0.67945 0.3048)
			(stroke
				(width 0.1)
				(type default)
			)
			(layer "F.Fab")
		)
		(fp_line
			(start 0.12065 -0.2794)
			(end 0.12065 -0.3048)
			(stroke
				(width 0.1)
				(type default)
			)
			(layer "F.Fab")
		)
		(fp_line
			(start 0.12065 -0.3048)
			(end 0.67945 -0.3048)
			(stroke
				(width 0.1)
				(type default)
			)
			(layer "F.Fab")
		)
		(fp_line
			(start 0.120396 0.3048)
			(end 0.120396 0.2794)
			(stroke
				(width 0.1)
				(type default)
			)
			(layer "F.Fab")
		)
		(fp_line
			(start 0.120396 0.2794)
			(end -0.12065 0.2794)
			(stroke
				(width 0.1)
				(type default)
			)
			(layer "F.Fab")
		)
		(fp_line
			(start -0.12065 0.3048)
			(end -0.67945 0.3048)
			(stroke
				(width 0.1)
				(type default)
			)
			(layer "F.Fab")
		)
		(fp_line
			(start -0.12065 0.2794)
			(end -0.12065 0.3048)
			(stroke
				(width 0.1)
				(type default)
			)
			(layer "F.Fab")
		)
		(fp_line
			(start -0.12065 -0.2794)
			(end 0.12065 -0.2794)
			(stroke
				(width 0.1)
				(type default)
			)
			(layer "F.Fab")
		)
		(fp_line
			(start -0.12065 -0.305054)
			(end -0.12065 -0.2794)
			(stroke
				(width 0.1)
				(type default)
			)
			(layer "F.Fab")
		)
		(fp_line
			(start -0.67945 0.3048)
			(end -0.67945 -0.305054)
			(stroke
				(width 0.1)
				(type default)
			)
			(layer "F.Fab")
		)
		(fp_line
			(start -0.67945 -0.305054)
			(end -0.12065 -0.305054)
			(stroke
				(width 0.1)
				(type default)
			)
			(layer "F.Fab")
		)
		(pad "1" smd circle
			(at -0.40005 0 180)
			(size 0 0)
			(layers "F.Cu" "F.Mask" "F.Paste")
			(net "P3V3_AUX")
		)
		(pad "2" smd circle
			(at 0.40005 0 180)
			(size 0 0)
			(layers "F.Cu" "F.Mask" "F.Paste")
			(net "PWRGD_P12V_SSD5")
		)
	)
	(footprint ""
		(layer "F.Cu")
		(at 11.01979 -303.088802)
		(property "Reference" "PC210"
			(at 0 0 0)
			(layer "F.SilkS")
			(hide yes)
			(effects
				(font
					(size 1.27 1.27)
				)
			)
		)
		(property "Value" ""
			(at 0 0 0)
			(layer "F.Fab")
			(effects
				(font
					(size 1.27 1.27)
				)
			)
		)
		(duplicate_pad_numbers_are_jumpers no)
		(fp_line
			(start -0.7874 -0.4064)
			(end 0.7874 -0.4064)
			(stroke
				(width 0.1524)
				(type default)
			)
			(layer "F.SilkS")
		)
		(fp_line
			(start -0.7874 0.4064)
			(end -0.7874 -0.4064)
			(stroke
				(width 0.1524)
				(type default)
			)
			(layer "F.SilkS")
		)
		(fp_line
			(start 0.7874 -0.4064)
			(end 0.7874 0.4064)
			(stroke
				(width 0.1524)
				(type default)
			)
			(layer "F.SilkS")
		)
		(fp_line
			(start 0.7874 0.4064)
			(end -0.7874 0.4064)
			(stroke
				(width 0.1524)
				(type default)
			)
			(layer "F.SilkS")
		)
		(fp_line
			(start -0.67945 -0.305054)
			(end -0.12065 -0.305054)
			(stroke
				(width 0.1)
				(type default)
			)
			(layer "F.Fab")
		)
		(fp_line
			(start -0.67945 0.3048)
			(end -0.67945 -0.305054)
			(stroke
				(width 0.1)
				(type default)
			)
			(layer "F.Fab")
		)
		(fp_line
			(start -0.12065 -0.305054)
			(end -0.12065 -0.2794)
			(stroke
				(width 0.1)
				(type default)
			)
			(layer "F.Fab")
		)
		(fp_line
			(start -0.12065 -0.2794)
			(end 0.12065 -0.2794)
			(stroke
				(width 0.1)
				(type default)
			)
			(layer "F.Fab")
		)
		(fp_line
			(start -0.12065 0.2794)
			(end -0.12065 0.3048)
			(stroke
				(width 0.1)
				(type default)
			)
			(layer "F.Fab")
		)
		(fp_line
			(start -0.12065 0.3048)
			(end -0.67945 0.3048)
			(stroke
				(width 0.1)
				(type default)
			)
			(layer "F.Fab")
		)
		(fp_line
			(start 0.120396 0.2794)
			(end -0.12065 0.2794)
			(stroke
				(width 0.1)
				(type default)
			)
			(layer "F.Fab")
		)
		(fp_line
			(start 0.120396 0.3048)
			(end 0.120396 0.2794)
			(stroke
				(width 0.1)
				(type default)
			)
			(layer "F.Fab")
		)
		(fp_line
			(start 0.12065 -0.3048)
			(end 0.67945 -0.3048)
			(stroke
				(width 0.1)
				(type default)
			)
			(layer "F.Fab")
		)
		(fp_line
			(start 0.12065 -0.2794)
			(end 0.12065 -0.3048)
			(stroke
				(width 0.1)
				(type default)
			)
			(layer "F.Fab")
		)
		(fp_line
			(start 0.67945 -0.3048)
			(end 0.67945 0.3048)
			(stroke
				(width 0.1)
				(type default)
			)
			(layer "F.Fab")
		)
		(fp_line
			(start 0.67945 0.3048)
			(end 0.120396 0.3048)
			(stroke
				(width 0.1)
				(type default)
			)
			(layer "F.Fab")
		)
		(pad "1" smd circle
			(at -0.40005 0)
			(size 0 0)
			(layers "F.Cu" "F.Mask" "F.Paste")
			(net "SW_P12V_P1V25_PEX0_FLT")
		)
		(pad "2" smd circle
			(at 0.40005 0)
			(size 0 0)
			(layers "F.Cu" "F.Mask" "F.Paste")
			(net "GND")
		)
	)
)
